#ISCELL
  logical_power cad_note *
  *
#ISCELL
  mstr_misc dns *
  *
#ISCELL
  pure_quanta quanta_title_block_c *
  *
#CELL
  pure_quanta q_res *
  page324_i1
#CELL
  pure_quanta mosfet_nch_dual *
  page324_i10
#ISCELL
  logical_power gnd *
  page324_i11
#ISCELL
  logical_power gnd *
  page324_i12
#CELL
  pure_quanta q_res *
  page324_i13
#CELL
  pure_quanta q_res *
  page324_i14
#CELL
  pure_quanta q_res *
  page324_i15
#ISCELL
  logical_power gnd *
  page324_i16
#CELL
  pure_quanta q_cap *
  page324_i17
#CELL
  pure_quanta q_res *
  page324_i18
#ISCELL
  logical_power universal_power *
  page324_i19
#ISCELL
  logical_power gnd *
  page324_i2
#ISCELL
  standard offpage *
  page324_i20
#CELL
  pure_quanta q_res *
  page324_i21
#CELL
  pure_quanta q_res *
  page324_i22
#ISCELL
  logical_power universal_power *
  page324_i23
#CELL
  pure_quanta mosfet_nch_dual *
  page324_i24
#ISCELL
  logical_power gnd *
  page324_i25
#CELL
  pure_quanta q_res *
  page324_i26
#ISCELL
  logical_power gnd *
  page324_i27
#CELL
  pure_quanta q_res *
  page324_i28
#ISCELL
  logical_power gnd *
  page324_i29
#CELL
  pure_quanta mosfet_nch_dual *
  page324_i3
#ISCELL
  logical_power universal_power *
  page324_i30
#CELL
  pure_quanta q_cap *
  page324_i31
#CELL
  pure_quanta q_res *
  page324_i32
#ISCELL
  logical_power gnd *
  page324_i33
#CELL
  pure_quanta q_res *
  page324_i34
#CELL
  pure_quanta max15090bewit *
  page324_i35
#ISCELL
  logical_power gnd *
  page324_i36
#CELL
  pure_quanta q_cap *
  page324_i37
#CELL
  pure_quanta q_cap *
  page324_i38
#CELL
  pure_quanta q_res *
  page324_i39
#CELL
  pure_quanta mosfet_nch_dual *
  page324_i4
#ISCELL
  logical_power gnd *
  page324_i40
#CELL
  pure_quanta q_res *
  page324_i41
#CELL
  pure_quanta q_cap *
  page324_i42
#CELL
  pure_quanta q_res *
  page324_i43
#CELL
  pure_quanta q_res *
  page324_i44
#CELL
  pure_quanta q_cap *
  page324_i45
#CELL
  pure_quanta schottky_ac *
  page324_i46
#ISCELL
  logical_power gnd *
  page324_i47
#CELL
  pure_quanta q_res *
  page324_i48
#ISCELL
  logical_power vccaux15 *
  page324_i49
#ISCELL
  logical_power gnd *
  page324_i5
#CELL
  pure_quanta q_res *
  page324_i50
#ISCELL
  logical_power gnd *
  page324_i51
#CELL
  pure_quanta q_cap *
  page324_i52
#CELL
  pure_quanta q_cap *
  page324_i53
#ISCELL
  logical_power universal_power *
  page324_i54
#ISCELL
  logical_power universal_power *
  page324_i55
#ISCELL
  logical_power gnd *
  page324_i56
#CELL
  pure_quanta q_cap *
  page324_i57
#ISCELL
  logical_power gnd *
  page324_i58
#CELL
  pure_quanta q_res *
  page324_i59
#CELL
  pure_quanta q_res *
  page324_i6
#CELL
  pure_quanta q_cap *
  page324_i60
#CELL
  pure_quanta q_res *
  page324_i61
#CELL
  pure_quanta max15090bewit *
  page324_i62
#ISCELL
  logical_power gnd *
  page324_i63
#CELL
  pure_quanta q_res *
  page324_i64
#CELL
  pure_quanta q_res *
  page324_i65
#CELL
  pure_quanta q_cap *
  page324_i66
#CELL
  pure_quanta q_res *
  page324_i67
#CELL
  pure_quanta q_res *
  page324_i68
#CELL
  pure_quanta q_cap *
  page324_i69
#ISCELL
  logical_power universal_power *
  page324_i7
#CELL
  pure_quanta q_res *
  page324_i70
#CELL
  pure_quanta schottky_ac *
  page324_i71
#ISCELL
  logical_power gnd *
  page324_i72
#CELL
  pure_quanta q_res *
  page324_i73
#ISCELL
  logical_power vccaux15 *
  page324_i74
#CELL
  pure_quanta q_cap *
  page324_i75
#CELL
  pure_quanta q_res *
  page324_i76
#ISCELL
  logical_power gnd *
  page324_i77
#CELL
  pure_quanta q_cap *
  page324_i78
#CELL
  pure_quanta q_cap *
  page324_i79
#ISCELL
  logical_power gnd *
  page324_i8
#ISCELL
  logical_power universal_power *
  page324_i80
#ISCELL
  standard offpage *
  page324_i81
#ISCELL
  standard offpage *
  page324_i82
#ISCELL
  standard offpage *
  page324_i83
#CELL
  pure_quanta diode_tvs *
  page324_i84
#CELL
  pure_quanta q_res *
  page324_i85
#CELL
  pure_quanta q_res *
  page324_i9
